# S9S_MB_2U (Grand Teton) — schematic netlist excerpt (pin names and nets, part order shuffled) for the footprints in the layout excerpt that follows; sources: Cadence DE-HDL packaged netlist, KiCad conversion of 03242023_DA0F0TMBIJ0_F0T_Motherboard_J_brd_V01_OCP.brd

C1207  Q_CAP  10UF 6.3V 20% X6S  pkg C0402  page 189 : A = P1V8_PCH_AUX ; B = GND
D46  SCHOTTKY_12  B0530WS7F IC  pkg SOD323XB  page 115 : A = PWRGD_FAIL_CPU1_AB_R1 ; C = P3V3_AUX

(kicad_pcb
	(version 20260206)
	(generator "pcbnew")
	(generator_version "10.0")
	(general
		(thickness 1.6)
		(legacy_teardrops no)
	)
	(paper "A4")
	(title_block
		(title "03242023_DA0F0TMBIJ0_F0T_Motherboard_J_brd_V01_OCP.brd")
		(comment 1 "Grand Teton / footprints 5941-5942 of 6105")
	)
	(layers
		(0 "F.Cu" signal "TOP")
		(4 "In1.Cu" signal "GND")
		(6 "In2.Cu" signal "IN1")
		(8 "In3.Cu" signal "GND1")
		(10 "In4.Cu" signal "IN2")
		(12 "In5.Cu" signal "GND2")
		(14 "In6.Cu" signal "IN3")
		(16 "In7.Cu" signal "GND3")
		(18 "In8.Cu" signal "VCC")
		(20 "In9.Cu" signal "VCC1")
		(22 "In10.Cu" signal "GND4")
		(24 "In11.Cu" signal "IN4")
		(26 "In12.Cu" signal "GND5")
		(28 "In13.Cu" signal "IN5")
		(30 "In14.Cu" signal "GND6")
		(32 "In15.Cu" signal "IN6")
		(34 "In16.Cu" signal "GND7")
		(2 "B.Cu" signal "BOTTOM")
		(9 "F.Adhes" user "F.Adhesive")
		(11 "B.Adhes" user "B.Adhesive")
		(13 "F.Paste" user "Package Geometry/Pastemask Top")
		(15 "B.Paste" user "Package Geometry/Pastemask Bottom")
		(5 "F.SilkS" user "Ref Des/Silkscreen Top")
		(7 "B.SilkS" user "Ref Des/Silkscreen Bottom")
		(1 "F.Mask" user "Board Geometry/Soldermask Top")
		(3 "B.Mask" user "Board Geometry/Soldermask Bottom")
		(17 "Dwgs.User" user "User.Drawings")
		(19 "Cmts.User" user "User.Comments")
		(21 "Eco1.User" user "User.Eco1")
		(23 "Eco2.User" user "User.Eco2")
		(25 "Edge.Cuts" user "Board Geometry/Outline")
		(27 "Margin" user)
		(31 "F.CrtYd" user "Package Geometry/Place Bound Top")
		(29 "B.CrtYd" user "Package Geometry/Place Bound Bottom")
		(35 "F.Fab" user "Ref Des/Assembly Top")
		(33 "B.Fab" user "Ref Des/Assembly Bottom")
	)
	(footprint ""
		(layer "B.Cu")
		(at 68.223638 -319.98539 -90)
		(property "Reference" "D46"
			(at -4.247388 -1.898142 0)
			(unlocked yes)
			(layer "B.SilkS")
			(effects
				(font
					(size 0.7874 0.5842)
					(thickness 0.1524)
				)
				(justify left mirror)
			)
		)
		(property "Value" ""
			(at 0 0 90)
			(layer "B.Fab")
			(effects
				(font
					(size 1.27 1.27)
				)
				(justify mirror)
			)
		)
		(duplicate_pad_numbers_are_jumpers no)
		(fp_line
			(start -2.050796 0.700024)
			(end 2.050796 0.700024)
			(stroke
				(width 0.1524)
				(type default)
			)
			(layer "B.SilkS")
		)
		(fp_line
			(start 2.050796 0.700024)
			(end 2.050796 -0.700024)
			(stroke
				(width 0.1524)
				(type default)
			)
			(layer "B.SilkS")
		)
		(fp_line
			(start -2.343404 0.6985)
			(end -2.216404 0.6985)
			(stroke
				(width 0.1524)
				(type default)
			)
			(layer "B.SilkS")
		)
		(fp_line
			(start -2.229104 0.6985)
			(end -2.051304 0.6985)
			(stroke
				(width 0.1524)
				(type default)
			)
			(layer "B.SilkS")
		)
		(fp_line
			(start -2.051304 0.6985)
			(end -2.051304 0.635)
			(stroke
				(width 0.1524)
				(type default)
			)
			(layer "B.SilkS")
		)
		(fp_line
			(start -2.152904 0.635)
			(end -2.152904 -0.6985)
			(stroke
				(width 0.1524)
				(type default)
			)
			(layer "B.SilkS")
		)
		(fp_line
			(start -2.051304 0.635)
			(end -2.152904 0.635)
			(stroke
				(width 0.1524)
				(type default)
			)
			(layer "B.SilkS")
		)
		(fp_line
			(start 0.30607 0.500126)
			(end -0.193802 0)
			(stroke
				(width 0.1524)
				(type default)
			)
			(layer "B.SilkS")
		)
		(fp_line
			(start -0.193802 0)
			(end 0.30607 -0.500126)
			(stroke
				(width 0.1524)
				(type default)
			)
			(layer "B.SilkS")
		)
		(fp_line
			(start -0.293878 -0.500126)
			(end -0.293878 0.500126)
			(stroke
				(width 0.1524)
				(type default)
			)
			(layer "B.SilkS")
		)
		(fp_line
			(start 0.30607 -0.500126)
			(end 0.30607 0.500126)
			(stroke
				(width 0.1524)
				(type default)
			)
			(layer "B.SilkS")
		)
		(fp_line
			(start -2.064004 -0.6731)
			(end -2.064004 -0.6985)
			(stroke
				(width 0.1524)
				(type default)
			)
			(layer "B.SilkS")
		)
		(fp_line
			(start -2.343404 -0.6985)
			(end -2.343404 0.6985)
			(stroke
				(width 0.1524)
				(type default)
			)
			(layer "B.SilkS")
		)
		(fp_line
			(start -2.229104 -0.6985)
			(end -2.229104 0.6985)
			(stroke
				(width 0.1524)
				(type default)
			)
			(layer "B.SilkS")
		)
		(fp_line
			(start -2.152904 -0.6985)
			(end -2.343404 -0.6985)
			(stroke
				(width 0.1524)
				(type default)
			)
			(layer "B.SilkS")
		)
		(fp_line
			(start -2.064004 -0.6985)
			(end -2.229104 -0.6985)
			(stroke
				(width 0.1524)
				(type default)
			)
			(layer "B.SilkS")
		)
		(fp_line
			(start -2.050796 -0.700024)
			(end -2.050796 0.700024)
			(stroke
				(width 0.1524)
				(type default)
			)
			(layer "B.SilkS")
		)
		(fp_line
			(start 2.050796 -0.700024)
			(end -2.050796 -0.700024)
			(stroke
				(width 0.1524)
				(type default)
			)
			(layer "B.SilkS")
		)
		(fp_line
			(start -0.899922 0.700024)
			(end 0.899922 0.700024)
			(stroke
				(width 0.1)
				(type default)
			)
			(layer "B.Fab")
		)
		(fp_line
			(start 0.899922 0.700024)
			(end 0.899922 -0.700024)
			(stroke
				(width 0.1)
				(type default)
			)
			(layer "B.Fab")
		)
		(fp_line
			(start -0.899922 -0.700024)
			(end -0.899922 0.700024)
			(stroke
				(width 0.1)
				(type default)
			)
			(layer "B.Fab")
		)
		(fp_line
			(start 0.899922 -0.700024)
			(end -0.899922 -0.700024)
			(stroke
				(width 0.1)
				(type default)
			)
			(layer "B.Fab")
		)
		(fp_text user "+"
			(at 3.123946 0.762 180)
			(unlocked yes)
			(layer "B.SilkS")
			(effects
				(font
					(size 1.905 1.4224)
					(thickness 0.1524)
				)
				(justify left mirror)
			)
		)
		(fp_text user "-"
			(at -3.880104 0.23495 90)
			(unlocked yes)
			(layer "B.SilkS")
			(effects
				(font
					(size 1.905 1.4224)
					(thickness 0.1524)
				)
				(justify left mirror)
			)
		)
		(fp_text user "+"
			(at 3.123946 0.762 180)
			(unlocked yes)
			(layer "B.Fab")
			(effects
				(font
					(size 1.905 1.4224)
					(thickness 0.1524)
				)
				(justify left mirror)
			)
		)
		(fp_text user "-"
			(at -3.880104 0.23495 90)
			(unlocked yes)
			(layer "B.Fab")
			(effects
				(font
					(size 1.905 1.4224)
					(thickness 0.1524)
				)
				(justify left mirror)
			)
		)
		(pad "1" smd rect
			(at 1.199896 0 180)
			(size 0.6604 1.3716)
			(layers "B.Cu" "B.Mask" "B.Paste")
			(net "PWRGD_FAIL_CPU1_AB_R1")
		)
		(pad "2" smd rect
			(at -1.199896 0)
			(size 0.6604 1.3716)
			(layers "B.Cu" "B.Mask" "B.Paste")
			(net "P3V3_AUX")
		)
	)
	(footprint ""
		(layer "B.Cu")
		(at 334.62849 -51.343814)
		(property "Reference" "C1207"
			(at 0 0 0)
			(layer "B.SilkS")
			(hide yes)
			(effects
				(font
					(size 1.27 1.27)
				)
				(justify mirror)
			)
		)
		(property "Value" ""
			(at 0 0 0)
			(layer "B.Fab")
			(effects
				(font
					(size 1.27 1.27)
				)
				(justify mirror)
			)
		)
		(duplicate_pad_numbers_are_jumpers no)
		(fp_line
			(start -0.7874 -0.4064)
			(end -0.7874 0.4064)
			(stroke
				(width 0.1524)
				(type default)
			)
			(layer "B.SilkS")
		)
		(fp_line
			(start -0.7874 0.4064)
			(end 0.7874 0.4064)
			(stroke
				(width 0.1524)
				(type default)
			)
			(layer "B.SilkS")
		)
		(fp_line
			(start 0.7874 -0.4064)
			(end -0.7874 -0.4064)
			(stroke
				(width 0.1524)
				(type default)
			)
			(layer "B.SilkS")
		)
		(fp_line
			(start 0.7874 0.4064)
			(end 0.7874 -0.4064)
			(stroke
				(width 0.1524)
				(type default)
			)
			(layer "B.SilkS")
		)
		(fp_line
			(start -0.67945 -0.3048)
			(end -0.67945 0.3048)
			(stroke
				(width 0.1)
				(type default)
			)
			(layer "B.Fab")
		)
		(fp_line
			(start -0.67945 0.3048)
			(end -0.120396 0.3048)
			(stroke
				(width 0.1)
				(type default)
			)
			(layer "B.Fab")
		)
		(fp_line
			(start -0.12065 -0.3048)
			(end -0.67945 -0.3048)
			(stroke
				(width 0.1)
				(type default)
			)
			(layer "B.Fab")
		)
		(fp_line
			(start -0.12065 -0.2794)
			(end -0.12065 -0.3048)
			(stroke
				(width 0.1)
				(type default)
			)
			(layer "B.Fab")
		)
		(fp_line
			(start -0.120396 0.2794)
			(end 0.12065 0.2794)
			(stroke
				(width 0.1)
				(type default)
			)
			(layer "B.Fab")
		)
		(fp_line
			(start -0.120396 0.3048)
			(end -0.120396 0.2794)
			(stroke
				(width 0.1)
				(type default)
			)
			(layer "B.Fab")
		)
		(fp_line
			(start 0.12065 -0.305054)
			(end 0.12065 -0.2794)
			(stroke
				(width 0.1)
				(type default)
			)
			(layer "B.Fab")
		)
		(fp_line
			(start 0.12065 -0.2794)
			(end -0.12065 -0.2794)
			(stroke
				(width 0.1)
				(type default)
			)
			(layer "B.Fab")
		)
		(fp_line
			(start 0.12065 0.2794)
			(end 0.12065 0.3048)
			(stroke
				(width 0.1)
				(type default)
			)
			(layer "B.Fab")
		)
		(fp_line
			(start 0.12065 0.3048)
			(end 0.67945 0.3048)
			(stroke
				(width 0.1)
				(type default)
			)
			(layer "B.Fab")
		)
		(fp_line
			(start 0.67945 -0.305054)
			(end 0.12065 -0.305054)
			(stroke
				(width 0.1)
				(type default)
			)
			(layer "B.Fab")
		)
		(fp_line
			(start 0.67945 0.3048)
			(end 0.67945 -0.305054)
			(stroke
				(width 0.1)
				(type default)
			)
			(layer "B.Fab")
		)
		(pad "1" smd circle
			(at 0.40005 0 180)
			(size 0 0)
			(layers "B.Cu" "B.Mask" "B.Paste")
			(net "P1V8_PCH_AUX")
		)
		(pad "2" smd circle
			(at -0.40005 0 180)
			(size 0 0)
			(layers "B.Cu" "B.Mask" "B.Paste")
			(net "GND")
		)
	)
)
